# T6G (Grand Teton) — schematic netlist excerpt (pin names and nets, part order shuffled) for the footprints in the layout excerpt that follows; sources: Cadence DE-HDL packaged netlist, KiCad conversion of 04192023_DAF0TMB3IC0_F0TG_MB_C_brd_V02_OCP.brd

PU24  ISL99390FRZTR5935  ISL99390FRZ-TR5935 IC  pkg QFN21_6X5XB  page 213
  VOS  = PVDDCR_CPU0_P1_VOS6
  AGND  = GND
  VCC  = PVDDCR_CPU0_P1_VCC6
  PVCC  = PVDDCR_CPU0_P1_PVCC
  PGND1  = GND
  GL1  = NC_PVDDCR_CPU0_P1_GL1_6
  PGND2  = GND
  SW  = SW_PVDDCR_CPU0_P1_SW6
  VIN1  = SW_P12V_AUX_PVDDCR_CPU0_P1_FLT
  VIN2  = SW_P12V_AUX_PVDDCR_CPU0_P1_FLT
  DNC  = NC_PVDDCR_CPU0_P1_DNC6
  PHASE  = SW_PVDDCR_CPU0_P1_PH6
  BOOT  = SW_PVDDCR_CPU0_P1_BOOT6
  PWM  = PVDDCR_CPU0_P1_PWM6
  EN  = PVDDCR_CPU0_P1_VCC6
  TOUT_FLT  = PVDDCR_CPU0_P1_TEMP0
  LSET  = PVDDCR_CPU0_P1_LSET6
  IOUT  = PVDDCR_CPU0_P1_IMON6
  REFIN  = PVDDCR_CPU0_P1_VCCS
  PGND3  = GND
  GL2  = NC_PVDDCR_CPU0_P1_GL2_6

(kicad_pcb
	(version 20260206)
	(generator "pcbnew")
	(generator_version "10.0")
	(general
		(thickness 1.6)
		(legacy_teardrops no)
	)
	(paper "A4")
	(title_block
		(title "04192023_DAF0TMB3IC0_F0TG_MB_C_brd_V02_OCP.brd")
		(comment 1 "Grand Teton / footprints 445-445 of 8354")
	)
	(layers
		(0 "F.Cu" signal "TOP")
		(4 "In1.Cu" signal "GND")
		(6 "In2.Cu" signal "IN1")
		(8 "In3.Cu" signal "GND1")
		(10 "In4.Cu" signal "IN2")
		(12 "In5.Cu" signal "GND2")
		(14 "In6.Cu" signal "IN3")
		(16 "In7.Cu" signal "GND3")
		(18 "In8.Cu" signal "VCC")
		(20 "In9.Cu" signal "VCC1")
		(22 "In10.Cu" signal "GND4")
		(24 "In11.Cu" signal "IN4")
		(26 "In12.Cu" signal "GND5")
		(28 "In13.Cu" signal "IN5")
		(30 "In14.Cu" signal "GND6")
		(32 "In15.Cu" signal "IN6")
		(34 "In16.Cu" signal "GND7")
		(2 "B.Cu" signal "BOTTOM")
		(9 "F.Adhes" user "F.Adhesive")
		(11 "B.Adhes" user "B.Adhesive")
		(13 "F.Paste" user "Package Geometry/Pastemask Top")
		(15 "B.Paste" user "Package Geometry/Pastemask Bottom")
		(5 "F.SilkS" user "Ref Des/Silkscreen Top")
		(7 "B.SilkS" user "Ref Des/Silkscreen Bottom")
		(1 "F.Mask" user "Board Geometry/Soldermask Top")
		(3 "B.Mask" user "Board Geometry/Soldermask Bottom")
		(17 "Dwgs.User" user "User.Drawings")
		(19 "Cmts.User" user "User.Comments")
		(21 "Eco1.User" user "User.Eco1")
		(23 "Eco2.User" user "User.Eco2")
		(25 "Edge.Cuts" user "Board Geometry/Outline")
		(27 "Margin" user)
		(31 "F.CrtYd" user "Package Geometry/Place Bound Top")
		(29 "B.CrtYd" user "Package Geometry/Place Bound Bottom")
		(35 "F.Fab" user "Ref Des/Assembly Top")
		(33 "B.Fab" user "Ref Des/Assembly Bottom")
	)
	(footprint ""
		(layer "F.Cu")
		(at 65.64757 -168.928542 180)
		(property "Reference" "PU24"
			(at -0.129032 -6.648704 0)
			(unlocked yes)
			(layer "F.SilkS")
			(effects
				(font
					(size 0.7874 0.5842)
					(thickness 0.1524)
				)
				(justify left)
			)
		)
		(property "Value" ""
			(at 0 0 180)
			(layer "F.Fab")
			(effects
				(font
					(size 1.27 1.27)
				)
			)
		)
		(duplicate_pad_numbers_are_jumpers no)
		(fp_line
			(start 2.500122 2.999994)
			(end 2.2987 2.999994)
			(stroke
				(width 0.1524)
				(type default)
			)
			(layer "F.SilkS")
		)
		(fp_line
			(start 2.500122 2.339594)
			(end 2.500122 2.999994)
			(stroke
				(width 0.1524)
				(type default)
			)
			(layer "F.SilkS")
		)
		(fp_line
			(start 2.500122 -2.999994)
			(end 2.500122 -2.44348)
			(stroke
				(width 0.1524)
				(type default)
			)
			(layer "F.SilkS")
		)
		(fp_line
			(start 2.31394 -2.999994)
			(end 2.500122 -2.999994)
			(stroke
				(width 0.1524)
				(type default)
			)
			(layer "F.SilkS")
		)
		(fp_line
			(start -2.2987 2.999994)
			(end -2.500122 2.999994)
			(stroke
				(width 0.1524)
				(type default)
			)
			(layer "F.SilkS")
		)
		(fp_line
			(start -2.500122 2.999994)
			(end -2.500122 2.339594)
			(stroke
				(width 0.1524)
				(type default)
			)
			(layer "F.SilkS")
		)
		(fp_line
			(start -2.500122 0.6604)
			(end -2.500122 0.229108)
			(stroke
				(width 0.1524)
				(type default)
			)
			(layer "F.SilkS")
		)
		(fp_line
			(start -2.500122 -2.529078)
			(end -2.500122 -2.999994)
			(stroke
				(width 0.1524)
				(type default)
			)
			(layer "F.SilkS")
		)
		(fp_line
			(start -2.500122 -2.999994)
			(end -2.24409 -2.999994)
			(stroke
				(width 0.1524)
				(type default)
			)
			(layer "F.SilkS")
		)
		(fp_poly
			(pts
				(xy -2.695956 -2.436622) (xy -3.492754 -2.702306) (xy -2.96164 -3.233166)
			)
			(stroke
				(width 0)
				(type default)
			)
			(fill yes)
			(layer "F.SilkS")
		)
		(fp_line
			(start 2.500122 2.999994)
			(end -2.500122 2.999994)
			(stroke
				(width 0.1)
				(type default)
			)
			(layer "F.Fab")
		)
		(fp_line
			(start 2.500122 -2.999994)
			(end 2.500122 2.999994)
			(stroke
				(width 0.1)
				(type default)
			)
			(layer "F.Fab")
		)
		(fp_line
			(start -2.500122 2.999994)
			(end -2.500122 -2.999994)
			(stroke
				(width 0.1)
				(type default)
			)
			(layer "F.Fab")
		)
		(fp_line
			(start -2.500122 -2.999994)
			(end 2.500122 -2.999994)
			(stroke
				(width 0.1)
				(type default)
			)
			(layer "F.Fab")
		)
		(fp_poly
			(pts
				(xy -4.218432 -2.783078) (xy -4.218432 -1.767078) (xy -3.202432 -2.275078)
			)
			(stroke
				(width 0)
				(type default)
			)
			(fill yes)
			(layer "F.Fab")
		)
		(pad "1" smd rect
			(at -2.400046 -2.275078 270)
			(size 0.2286 0.6096)
			(layers "F.Cu" "F.Mask" "F.Paste")
			(net "PVDDCR_CPU0_P1_VOS6")
		)
		(pad "2" smd rect
			(at -2.400046 -1.82499 270)
			(size 0.2286 0.6096)
			(layers "F.Cu" "F.Mask" "F.Paste")
			(net "GND")
		)
		(pad "3" smd rect
			(at -2.400046 -1.374902 270)
			(size 0.2286 0.6096)
			(layers "F.Cu" "F.Mask" "F.Paste")
			(net "PVDDCR_CPU0_P1_VCC6")
		)
		(pad "4" smd rect
			(at -2.400046 -0.925068 270)
			(size 0.2286 0.6096)
			(layers "F.Cu" "F.Mask" "F.Paste")
			(net "PVDDCR_CPU0_P1_PVCC")
		)
		(pad "5" smd rect
			(at -2.400046 -0.47498 270)
			(size 0.2286 0.6096)
			(layers "F.Cu" "F.Mask" "F.Paste")
			(net "GND")
		)
		(pad "6" smd rect
			(at -2.400046 -0.024892 270)
			(size 0.2286 0.6096)
			(layers "F.Cu" "F.Mask" "F.Paste")
			(net "NC_PVDDCR_CPU0_P1_GL1_6")
		)
		(pad "7_9-20_24" smd circle
			(at 0 1.150112 270)
			(size 0 0)
			(layers "F.Cu" "F.Mask" "F.Paste")
			(net "GND")
		)
		(pad "10_19" smd rect
			(at 0 2.899918 270)
			(size 0.6096 4.318)
			(layers "F.Cu" "F.Mask" "F.Paste")
			(net "SW_PVDDCR_CPU0_P1_SW6")
		)
		(pad "25_29" smd rect
			(at 1.549908 -1.279906 90)
			(size 2.0574 2.3114)
			(layers "F.Cu" "F.Mask" "F.Paste")
			(net "SW_P12V_AUX_PVDDCR_CPU0_P1_FLT")
		)
		(pad "30" smd rect
			(at 2.05994 -2.899918 180)
			(size 0.2286 0.6096)
			(layers "F.Cu" "F.Mask" "F.Paste")
			(net "SW_P12V_AUX_PVDDCR_CPU0_P1_FLT")
		)
		(pad "31" smd rect
			(at 1.610106 -2.899918 180)
			(size 0.2286 0.6096)
			(layers "F.Cu" "F.Mask" "F.Paste")
			(net "NC_PVDDCR_CPU0_P1_DNC6")
		)
		(pad "32" smd rect
			(at 1.160018 -2.899918 180)
			(size 0.2286 0.6096)
			(layers "F.Cu" "F.Mask" "F.Paste")
			(net "SW_PVDDCR_CPU0_P1_PH6")
		)
		(pad "33" smd rect
			(at 0.70993 -2.899918 180)
			(size 0.2286 0.6096)
			(layers "F.Cu" "F.Mask" "F.Paste")
			(net "SW_PVDDCR_CPU0_P1_BOOT6")
		)
		(pad "34" smd rect
			(at 0.260096 -2.899918 180)
			(size 0.2286 0.6096)
			(layers "F.Cu" "F.Mask" "F.Paste")
			(net "PVDDCR_CPU0_P1_PWM6")
		)
		(pad "35" smd rect
			(at -0.189992 -2.899918 180)
			(size 0.2286 0.6096)
			(layers "F.Cu" "F.Mask" "F.Paste")
			(net "PVDDCR_CPU0_P1_VCC6")
		)
		(pad "36" smd rect
			(at -0.64008 -2.899918 180)
			(size 0.2286 0.6096)
			(layers "F.Cu" "F.Mask" "F.Paste")
			(net "PVDDCR_CPU0_P1_TEMP0")
		)
		(pad "37" smd rect
			(at -1.089914 -2.899918 180)
			(size 0.2286 0.6096)
			(layers "F.Cu" "F.Mask" "F.Paste")
			(net "PVDDCR_CPU0_P1_LSET6")
		)
		(pad "38" smd rect
			(at -1.540002 -2.899918 180)
			(size 0.2286 0.6096)
			(layers "F.Cu" "F.Mask" "F.Paste")
			(net "PVDDCR_CPU0_P1_IMON6")
		)
		(pad "39" smd rect
			(at -1.99009 -2.899918 180)
			(size 0.2286 0.6096)
			(layers "F.Cu" "F.Mask" "F.Paste")
			(net "PVDDCR_CPU0_P1_VCCS")
		)
		(pad "40" smd rect
			(at -0.87503 -1.27508 180)
			(size 1.7526 1.9558)
			(layers "F.Cu" "F.Mask" "F.Paste")
			(net "GND")
		)
		(pad "41" smd rect
			(at -1.525016 0.249936 90)
			(size 0.3048 0.4572)
			(layers "F.Cu" "F.Mask" "F.Paste")
			(net "NC_PVDDCR_CPU0_P1_GL2_6")
		)
		(zone
			(layer "F.Cu")
			(hatch none 0.5)
			(connect_pads
				(clearance 0)
			)
			(min_thickness 0.25)
			(keepout
				(tracks not_allowed)
				(vias allowed)
				(pads allowed)
				(copperpour not_allowed)
				(footprints allowed)
			)
			(placement
				(enabled no)
				(sheetname "")
			)
			(fill
				(thermal_gap 0.5)
				(thermal_bridge_width 0.5)
				(island_removal_mode 0)
			)
			(polygon
				(pts
					(xy 68.147692 -171.47286) (xy 68.147692 -171.179236) (xy 63.147448 -171.179236) (xy 63.147448 -171.47286)
					(xy 63.43777 -171.47286) (xy 67.85737 -171.47286)
				)
			)
		)
		(zone
			(layer "F.Cu")
			(hatch none 0.5)
			(connect_pads
				(clearance 0)
			)
			(min_thickness 0.25)
			(keepout
				(tracks not_allowed)
				(vias allowed)
				(pads allowed)
				(copperpour not_allowed)
				(footprints allowed)
			)
			(placement
				(enabled no)
				(sheetname "")
			)
			(fill
				(thermal_gap 0.5)
				(thermal_bridge_width 0.5)
				(island_removal_mode 0)
			)
			(polygon
				(pts
					(xy 65.5955 -168.682162) (xy 65.5955 -166.624762) (xy 67.4497 -166.624762) (xy 67.4497 -166.865808)
					(xy 67.692016 -166.865808) (xy 67.692016 -166.384224) (xy 63.80353 -166.384224) (xy 63.80353 -166.569136)
					(xy 65.304162 -166.569136) (xy 65.304162 -168.728136) (xy 63.147448 -168.728136) (xy 63.147448 -168.977818)
					(xy 65.299844 -168.977818)
				)
			)
		)
	)
)
